(kicad_pcb
	(version 20260206)
	(generator "pcbnew")
	(generator_version "10.0")
	(general
		(thickness 1.6)
		(legacy_teardrops no)
	)
	(paper "A4")
	(title_block
		(title "01162023_DA0F0TEBIF0_F0T_Expander_BD_F_brd_V02_OCP.brd")
		(comment 1 "Grand Teton / footprints 1894-1898 of 9728")
	)
	(layers
		(0 "F.Cu" signal "TOP")
		(4 "In1.Cu" signal "GND")
		(6 "In2.Cu" signal "VCC")
		(8 "In3.Cu" signal "VCC1")
		(10 "In4.Cu" signal "GND1")
		(12 "In5.Cu" signal "IN1")
		(14 "In6.Cu" signal "GND2")
		(16 "In7.Cu" signal "IN2")
		(18 "In8.Cu" signal "GND3")
		(20 "In9.Cu" signal "IN3")
		(22 "In10.Cu" signal "GND4")
		(24 "In11.Cu" signal "IN4")
		(26 "In12.Cu" signal "GND5")
		(28 "In13.Cu" signal "IN5")
		(30 "In14.Cu" signal "GND6")
		(32 "In15.Cu" signal "IN6")
		(34 "In16.Cu" signal "GND7")
		(2 "B.Cu" signal "BOTTOM")
		(9 "F.Adhes" user "F.Adhesive")
		(11 "B.Adhes" user "B.Adhesive")
		(13 "F.Paste" user "Package Geometry/Pastemask Top")
		(15 "B.Paste" user "Package Geometry/Pastemask Bottom")
		(5 "F.SilkS" user "Ref Des/Silkscreen Top")
		(7 "B.SilkS" user "Ref Des/Silkscreen Bottom")
		(1 "F.Mask" user "Board Geometry/Soldermask Top")
		(3 "B.Mask" user "Board Geometry/Soldermask Bottom")
		(17 "Dwgs.User" user "User.Drawings")
		(19 "Cmts.User" user "User.Comments")
		(21 "Eco1.User" user "User.Eco1")
		(23 "Eco2.User" user "User.Eco2")
		(25 "Edge.Cuts" user "Board Geometry/Outline")
		(27 "Margin" user)
		(31 "F.CrtYd" user "Package Geometry/Place Bound Top")
		(29 "B.CrtYd" user "Package Geometry/Place Bound Bottom")
		(35 "F.Fab" user "Ref Des/Assembly Top")
		(33 "B.Fab" user "Ref Des/Assembly Bottom")
	)
	(footprint ""
		(layer "F.Cu")
		(at 78.243684 -47.92091)
		(property "Reference" "R526"
			(at 0 0 0)
			(layer "F.SilkS")
			(hide yes)
			(effects
				(font
					(size 1.27 1.27)
				)
			)
		)
		(property "Value" ""
			(at 0 0 0)
			(layer "F.Fab")
			(effects
				(font
					(size 1.27 1.27)
				)
			)
		)
		(duplicate_pad_numbers_are_jumpers no)
		(fp_line
			(start -0.7874 -0.4064)
			(end 0.7874 -0.4064)
			(stroke
				(width 0.1524)
				(type default)
			)
			(layer "F.SilkS")
		)
		(fp_line
			(start -0.7874 0.4064)
			(end -0.7874 -0.4064)
			(stroke
				(width 0.1524)
				(type default)
			)
			(layer "F.SilkS")
		)
		(fp_line
			(start 0.7874 -0.4064)
			(end 0.7874 0.4064)
			(stroke
				(width 0.1524)
				(type default)
			)
			(layer "F.SilkS")
		)
		(fp_line
			(start 0.7874 0.4064)
			(end -0.7874 0.4064)
			(stroke
				(width 0.1524)
				(type default)
			)
			(layer "F.SilkS")
		)
		(fp_line
			(start -0.67945 -0.305054)
			(end -0.12065 -0.305054)
			(stroke
				(width 0.1)
				(type default)
			)
			(layer "F.Fab")
		)
		(fp_line
			(start -0.67945 0.3048)
			(end -0.67945 -0.305054)
			(stroke
				(width 0.1)
				(type default)
			)
			(layer "F.Fab")
		)
		(fp_line
			(start -0.12065 -0.305054)
			(end -0.12065 -0.2794)
			(stroke
				(width 0.1)
				(type default)
			)
			(layer "F.Fab")
		)
		(fp_line
			(start -0.12065 -0.2794)
			(end 0.12065 -0.2794)
			(stroke
				(width 0.1)
				(type default)
			)
			(layer "F.Fab")
		)
		(fp_line
			(start -0.12065 0.2794)
			(end -0.12065 0.3048)
			(stroke
				(width 0.1)
				(type default)
			)
			(layer "F.Fab")
		)
		(fp_line
			(start -0.12065 0.3048)
			(end -0.67945 0.3048)
			(stroke
				(width 0.1)
				(type default)
			)
			(layer "F.Fab")
		)
		(fp_line
			(start 0.120396 0.2794)
			(end -0.12065 0.2794)
			(stroke
				(width 0.1)
				(type default)
			)
			(layer "F.Fab")
		)
		(fp_line
			(start 0.120396 0.3048)
			(end 0.120396 0.2794)
			(stroke
				(width 0.1)
				(type default)
			)
			(layer "F.Fab")
		)
		(fp_line
			(start 0.12065 -0.3048)
			(end 0.67945 -0.3048)
			(stroke
				(width 0.1)
				(type default)
			)
			(layer "F.Fab")
		)
		(fp_line
			(start 0.12065 -0.2794)
			(end 0.12065 -0.3048)
			(stroke
				(width 0.1)
				(type default)
			)
			(layer "F.Fab")
		)
		(fp_line
			(start 0.67945 -0.3048)
			(end 0.67945 0.3048)
			(stroke
				(width 0.1)
				(type default)
			)
			(layer "F.Fab")
		)
		(fp_line
			(start 0.67945 0.3048)
			(end 0.120396 0.3048)
			(stroke
				(width 0.1)
				(type default)
			)
			(layer "F.Fab")
		)
		(pad "1" smd circle
			(at -0.40005 0)
			(size 0 0)
			(layers "F.Cu" "F.Mask" "F.Paste")
			(net "P3V3_AUX")
		)
		(pad "2" smd circle
			(at 0.40005 0)
			(size 0 0)
			(layers "F.Cu" "F.Mask" "F.Paste")
			(net "SSD_0_7_ADC_ALERT_N")
		)
	)
	(footprint ""
		(layer "F.Cu")
		(at 280.160984 -37.951156)
		(property "Reference" "Q226"
			(at -0.049784 -1.823974 0)
			(unlocked yes)
			(layer "F.SilkS")
			(effects
				(font
					(size 0.7874 0.5842)
					(thickness 0.1524)
				)
			)
		)
		(property "Value" ""
			(at 0 0 0)
			(layer "F.Fab")
			(effects
				(font
					(size 1.27 1.27)
				)
			)
		)
		(duplicate_pad_numbers_are_jumpers no)
		(fp_line
			(start -1.376172 -1.199896)
			(end -0.508 -1.199896)
			(stroke
				(width 0.1524)
				(type default)
			)
			(layer "F.SilkS")
		)
		(fp_line
			(start -1.376172 1.199896)
			(end -1.376172 -1.199896)
			(stroke
				(width 0.1524)
				(type default)
			)
			(layer "F.SilkS")
		)
		(fp_line
			(start -0.508 -1.199896)
			(end 0 -0.762)
			(stroke
				(width 0.1524)
				(type default)
			)
			(layer "F.SilkS")
		)
		(fp_line
			(start 0 -0.762)
			(end 0.508 -1.199896)
			(stroke
				(width 0.1524)
				(type default)
			)
			(layer "F.SilkS")
		)
		(fp_line
			(start 0.508 -1.199896)
			(end 1.376172 -1.199896)
			(stroke
				(width 0.1524)
				(type default)
			)
			(layer "F.SilkS")
		)
		(fp_line
			(start 1.376172 -1.199896)
			(end 1.376172 1.199896)
			(stroke
				(width 0.1524)
				(type default)
			)
			(layer "F.SilkS")
		)
		(fp_line
			(start 1.376172 1.199896)
			(end -1.376172 1.199896)
			(stroke
				(width 0.1524)
				(type default)
			)
			(layer "F.SilkS")
		)
		(fp_poly
			(pts
				(xy -1.506982 -0.950468) (xy -1.776476 -1.758696) (xy -2.31521 -1.219708)
			)
			(stroke
				(width 0)
				(type default)
			)
			(fill yes)
			(layer "F.SilkS")
		)
		(fp_line
			(start -0.674878 -1.100074)
			(end 0.674878 -1.100074)
			(stroke
				(width 0.1)
				(type default)
			)
			(layer "F.Fab")
		)
		(fp_line
			(start -0.674878 1.100074)
			(end -0.674878 -1.100074)
			(stroke
				(width 0.1)
				(type default)
			)
			(layer "F.Fab")
		)
		(fp_line
			(start 0.674878 -1.100074)
			(end 0.674878 1.100074)
			(stroke
				(width 0.1)
				(type default)
			)
			(layer "F.Fab")
		)
		(fp_line
			(start 0.674878 1.100074)
			(end -0.674878 1.100074)
			(stroke
				(width 0.1)
				(type default)
			)
			(layer "F.Fab")
		)
		(fp_poly
			(pts
				(xy -1.4605 -0.7493) (xy -2.2225 -1.1303) (xy -2.2225 -0.3683)
			)
			(stroke
				(width 0)
				(type default)
			)
			(fill yes)
			(layer "F.Fab")
		)
		(pad "1" smd rect
			(at -0.899922 -0.750062 270)
			(size 0.6096 0.6096)
			(layers "F.Cu" "F.Mask" "F.Paste")
			(net "GND")
		)
		(pad "2" smd rect
			(at -0.899922 0 270)
			(size 0.4064 0.6096)
			(layers "F.Cu" "F.Mask" "F.Paste")
			(net "P3V3_SSD10_PG_G1")
		)
		(pad "3" smd rect
			(at -0.899922 0.750062 270)
			(size 0.6096 0.6096)
			(layers "F.Cu" "F.Mask" "F.Paste")
			(net "PWRGD_P3V3_SSD10_D")
		)
		(pad "4" smd rect
			(at 0.899922 0.750062 270)
			(size 0.6096 0.6096)
			(layers "F.Cu" "F.Mask" "F.Paste")
			(net "GND")
		)
		(pad "5" smd rect
			(at 0.899922 0 270)
			(size 0.4064 0.6096)
			(layers "F.Cu" "F.Mask" "F.Paste")
			(net "P3V3_SSD10_PG_G2")
		)
		(pad "6" smd rect
			(at 0.899922 -0.750062 270)
			(size 0.6096 0.6096)
			(layers "F.Cu" "F.Mask" "F.Paste")
			(net "P3V3_SSD10_PG_G2")
		)
	)
	(footprint ""
		(layer "F.Cu")
		(at 213.809072 -221.350586 180)
		(property "Reference" "R4886"
			(at 0 0 180)
			(layer "F.SilkS")
			(hide yes)
			(effects
				(font
					(size 1.27 1.27)
				)
			)
		)
		(property "Value" ""
			(at 0 0 180)
			(layer "F.Fab")
			(effects
				(font
					(size 1.27 1.27)
				)
			)
		)
		(duplicate_pad_numbers_are_jumpers no)
		(fp_line
			(start 0.7874 0.4064)
			(end -0.7874 0.4064)
			(stroke
				(width 0.1524)
				(type default)
			)
			(layer "F.SilkS")
		)
		(fp_line
			(start 0.7874 -0.4064)
			(end 0.7874 0.4064)
			(stroke
				(width 0.1524)
				(type default)
			)
			(layer "F.SilkS")
		)
		(fp_line
			(start -0.7874 0.4064)
			(end -0.7874 -0.4064)
			(stroke
				(width 0.1524)
				(type default)
			)
			(layer "F.SilkS")
		)
		(fp_line
			(start -0.7874 -0.4064)
			(end 0.7874 -0.4064)
			(stroke
				(width 0.1524)
				(type default)
			)
			(layer "F.SilkS")
		)
		(fp_line
			(start 0.67945 0.3048)
			(end 0.120396 0.3048)
			(stroke
				(width 0.1)
				(type default)
			)
			(layer "F.Fab")
		)
		(fp_line
			(start 0.67945 -0.3048)
			(end 0.67945 0.3048)
			(stroke
				(width 0.1)
				(type default)
			)
			(layer "F.Fab")
		)
		(fp_line
			(start 0.12065 -0.2794)
			(end 0.12065 -0.3048)
			(stroke
				(width 0.1)
				(type default)
			)
			(layer "F.Fab")
		)
		(fp_line
			(start 0.12065 -0.3048)
			(end 0.67945 -0.3048)
			(stroke
				(width 0.1)
				(type default)
			)
			(layer "F.Fab")
		)
		(fp_line
			(start 0.120396 0.3048)
			(end 0.120396 0.2794)
			(stroke
				(width 0.1)
				(type default)
			)
			(layer "F.Fab")
		)
		(fp_line
			(start 0.120396 0.2794)
			(end -0.12065 0.2794)
			(stroke
				(width 0.1)
				(type default)
			)
			(layer "F.Fab")
		)
		(fp_line
			(start -0.12065 0.3048)
			(end -0.67945 0.3048)
			(stroke
				(width 0.1)
				(type default)
			)
			(layer "F.Fab")
		)
		(fp_line
			(start -0.12065 0.2794)
			(end -0.12065 0.3048)
			(stroke
				(width 0.1)
				(type default)
			)
			(layer "F.Fab")
		)
		(fp_line
			(start -0.12065 -0.2794)
			(end 0.12065 -0.2794)
			(stroke
				(width 0.1)
				(type default)
			)
			(layer "F.Fab")
		)
		(fp_line
			(start -0.12065 -0.305054)
			(end -0.12065 -0.2794)
			(stroke
				(width 0.1)
				(type default)
			)
			(layer "F.Fab")
		)
		(fp_line
			(start -0.67945 0.3048)
			(end -0.67945 -0.305054)
			(stroke
				(width 0.1)
				(type default)
			)
			(layer "F.Fab")
		)
		(fp_line
			(start -0.67945 -0.305054)
			(end -0.12065 -0.305054)
			(stroke
				(width 0.1)
				(type default)
			)
			(layer "F.Fab")
		)
		(pad "1" smd circle
			(at -0.40005 0 180)
			(size 0 0)
			(layers "F.Cu" "F.Mask" "F.Paste")
			(net "SMB_BIC_I2C9_SSD_MUX_R_SDA")
		)
		(pad "2" smd circle
			(at 0.40005 0 180)
			(size 0 0)
			(layers "F.Cu" "F.Mask" "F.Paste")
			(net "P3V3_AUX")
		)
	)
	(footprint ""
		(layer "F.Cu")
		(at 19.740118 -225.49993 180)
		(property "Reference" "U317"
			(at 1.629918 -8.386064 0)
			(unlocked yes)
			(layer "F.SilkS")
			(effects
				(font
					(size 0.7874 0.5842)
					(thickness 0.1524)
				)
				(justify left)
			)
		)
		(property "Value" ""
			(at 0 0 180)
			(layer "F.Fab")
			(effects
				(font
					(size 1.27 1.27)
				)
			)
		)
		(duplicate_pad_numbers_are_jumpers no)
		(fp_line
			(start 3.795014 5.2451)
			(end 3.795014 -5.2451)
			(stroke
				(width 0.1524)
				(type default)
			)
			(layer "F.SilkS")
		)
		(fp_line
			(start 3.795014 -5.2451)
			(end 1.9431 -5.2451)
			(stroke
				(width 0.1524)
				(type default)
			)
			(layer "F.SilkS")
		)
		(fp_line
			(start 1.9431 -5.2451)
			(end 0 -3.302)
			(stroke
				(width 0.1524)
				(type default)
			)
			(layer "F.SilkS")
		)
		(fp_line
			(start 0 -3.302)
			(end -1.9431 -5.2451)
			(stroke
				(width 0.1524)
				(type default)
			)
			(layer "F.SilkS")
		)
		(fp_line
			(start -1.9431 -5.2451)
			(end -3.795014 -5.2451)
			(stroke
				(width 0.1524)
				(type default)
			)
			(layer "F.SilkS")
		)
		(fp_line
			(start -3.795014 5.2451)
			(end 3.795014 5.2451)
			(stroke
				(width 0.1524)
				(type default)
			)
			(layer "F.SilkS")
		)
		(fp_line
			(start -3.795014 -5.2451)
			(end -3.795014 5.2451)
			(stroke
				(width 0.1524)
				(type default)
			)
			(layer "F.SilkS")
		)
		(fp_poly
			(pts
				(xy -5.976366 -4.445) (xy -7.239 -3.81381) (xy -7.239 -5.07619)
			)
			(stroke
				(width 0)
				(type default)
			)
			(fill yes)
			(layer "F.SilkS")
		)
		(fp_line
			(start 3.795014 5.2451)
			(end 3.795014 -5.2451)
			(stroke
				(width 0.1)
				(type default)
			)
			(layer "F.Fab")
		)
		(fp_line
			(start 3.795014 -5.2451)
			(end -3.795014 -5.2451)
			(stroke
				(width 0.1)
				(type default)
			)
			(layer "F.Fab")
		)
		(fp_line
			(start -3.795014 5.2451)
			(end 3.795014 5.2451)
			(stroke
				(width 0.1)
				(type default)
			)
			(layer "F.Fab")
		)
		(fp_line
			(start -3.795014 -5.2451)
			(end -3.795014 5.2451)
			(stroke
				(width 0.1)
				(type default)
			)
			(layer "F.Fab")
		)
		(fp_poly
			(pts
				(xy -5.976366 -4.445) (xy -7.239 -3.81381) (xy -7.239 -5.07619)
			)
			(stroke
				(width 0)
				(type default)
			)
			(fill yes)
			(layer "F.Fab")
		)
		(pad "1" smd rect
			(at -4.880102 -4.445 90)
			(size 0.8128 1.905)
			(layers "F.Cu" "F.Mask" "F.Paste")
			(net "SPI_PEX0_SDIO3_R1")
		)
		(pad "2" smd rect
			(at -4.880102 -3.175 90)
			(size 0.8128 1.905)
			(layers "F.Cu" "F.Mask" "F.Paste")
			(net "P1V8_PEX")
		)
		(pad "3" smd rect
			(at -4.880102 -1.905 90)
			(size 0.8128 1.905)
			(layers "F.Cu" "F.Mask" "F.Paste")
			(net "SPI_PEX0_RST_R_N")
		)
		(pad "4" smd rect
			(at -4.880102 -0.635 90)
			(size 0.8128 1.905)
			(layers "F.Cu" "F.Mask" "F.Paste")
			(net "Net_9021")
		)
		(pad "5" smd rect
			(at -4.880102 0.635 90)
			(size 0.8128 1.905)
			(layers "F.Cu" "F.Mask" "F.Paste")
			(net "Net_9020")
		)
		(pad "6" smd rect
			(at -4.880102 1.905 90)
			(size 0.8128 1.905)
			(layers "F.Cu" "F.Mask" "F.Paste")
			(net "Net_9019")
		)
		(pad "7" smd rect
			(at -4.880102 3.175 90)
			(size 0.8128 1.905)
			(layers "F.Cu" "F.Mask" "F.Paste")
			(net "SPI_PEX0_CS_MUX_R_N")
		)
		(pad "8" smd rect
			(at -4.880102 4.445 90)
			(size 0.8128 1.905)
			(layers "F.Cu" "F.Mask" "F.Paste")
			(net "SPI_PEX0_SDIO1_MUX_R")
		)
		(pad "9" smd rect
			(at 4.880102 4.445 270)
			(size 0.8128 1.905)
			(layers "F.Cu" "F.Mask" "F.Paste")
			(net "SPI_PEX0_SDIO2_R1")
		)
		(pad "10" smd rect
			(at 4.880102 3.175 270)
			(size 0.8128 1.905)
			(layers "F.Cu" "F.Mask" "F.Paste")
			(net "GND")
		)
		(pad "11" smd rect
			(at 4.880102 1.905 270)
			(size 0.8128 1.905)
			(layers "F.Cu" "F.Mask" "F.Paste")
			(net "Net_9018")
		)
		(pad "12" smd rect
			(at 4.880102 0.635 270)
			(size 0.8128 1.905)
			(layers "F.Cu" "F.Mask" "F.Paste")
			(net "Net_9017")
		)
		(pad "13" smd rect
			(at 4.880102 -0.635 270)
			(size 0.8128 1.905)
			(layers "F.Cu" "F.Mask" "F.Paste")
			(net "Net_9016")
		)
		(pad "14" smd rect
			(at 4.880102 -1.905 270)
			(size 0.8128 1.905)
			(layers "F.Cu" "F.Mask" "F.Paste")
			(net "Net_9015")
		)
		(pad "15" smd rect
			(at 4.880102 -3.175 270)
			(size 0.8128 1.905)
			(layers "F.Cu" "F.Mask" "F.Paste")
			(net "SPI_PEX0_SDIO0_MUX_R")
		)
		(pad "16" smd rect
			(at 4.880102 -4.445 270)
			(size 0.8128 1.905)
			(layers "F.Cu" "F.Mask" "F.Paste")
			(net "SPI_PEX0_CLK_MUX_R")
		)
	)
	(footprint ""
		(layer "F.Cu")
		(at 83.034124 -7.062724)
		(property "Reference" "R5805"
			(at 0 0 0)
			(layer "F.SilkS")
			(hide yes)
			(effects
				(font
					(size 1.27 1.27)
				)
			)
		)
		(property "Value" ""
			(at 0 0 0)
			(layer "F.Fab")
			(effects
				(font
					(size 1.27 1.27)
				)
			)
		)
		(duplicate_pad_numbers_are_jumpers no)
		(fp_line
			(start -0.7874 -0.4064)
			(end 0.7874 -0.4064)
			(stroke
				(width 0.1524)
				(type default)
			)
			(layer "F.SilkS")
		)
		(fp_line
			(start -0.7874 0.4064)
			(end -0.7874 -0.4064)
			(stroke
				(width 0.1524)
				(type default)
			)
			(layer "F.SilkS")
		)
		(fp_line
			(start 0.7874 -0.4064)
			(end 0.7874 0.4064)
			(stroke
				(width 0.1524)
				(type default)
			)
			(layer "F.SilkS")
		)
		(fp_line
			(start 0.7874 0.4064)
			(end -0.7874 0.4064)
			(stroke
				(width 0.1524)
				(type default)
			)
			(layer "F.SilkS")
		)
		(fp_line
			(start -0.67945 -0.305054)
			(end -0.12065 -0.305054)
			(stroke
				(width 0.1)
				(type default)
			)
			(layer "F.Fab")
		)
		(fp_line
			(start -0.67945 0.3048)
			(end -0.67945 -0.305054)
			(stroke
				(width 0.1)
				(type default)
			)
			(layer "F.Fab")
		)
		(fp_line
			(start -0.12065 -0.305054)
			(end -0.12065 -0.2794)
			(stroke
				(width 0.1)
				(type default)
			)
			(layer "F.Fab")
		)
		(fp_line
			(start -0.12065 -0.2794)
			(end 0.12065 -0.2794)
			(stroke
				(width 0.1)
				(type default)
			)
			(layer "F.Fab")
		)
		(fp_line
			(start -0.12065 0.2794)
			(end -0.12065 0.3048)
			(stroke
				(width 0.1)
				(type default)
			)
			(layer "F.Fab")
		)
		(fp_line
			(start -0.12065 0.3048)
			(end -0.67945 0.3048)
			(stroke
				(width 0.1)
				(type default)
			)
			(layer "F.Fab")
		)
		(fp_line
			(start 0.120396 0.2794)
			(end -0.12065 0.2794)
			(stroke
				(width 0.1)
				(type default)
			)
			(layer "F.Fab")
		)
		(fp_line
			(start 0.120396 0.3048)
			(end 0.120396 0.2794)
			(stroke
				(width 0.1)
				(type default)
			)
			(layer "F.Fab")
		)
		(fp_line
			(start 0.12065 -0.3048)
			(end 0.67945 -0.3048)
			(stroke
				(width 0.1)
				(type default)
			)
			(layer "F.Fab")
		)
		(fp_line
			(start 0.12065 -0.2794)
			(end 0.12065 -0.3048)
			(stroke
				(width 0.1)
				(type default)
			)
			(layer "F.Fab")
		)
		(fp_line
			(start 0.67945 -0.3048)
			(end 0.67945 0.3048)
			(stroke
				(width 0.1)
				(type default)
			)
			(layer "F.Fab")
		)
		(fp_line
			(start 0.67945 0.3048)
			(end 0.120396 0.3048)
			(stroke
				(width 0.1)
				(type default)
			)
			(layer "F.Fab")
		)
		(pad "1" smd circle
			(at -0.40005 0)
			(size 0 0)
			(layers "F.Cu" "F.Mask" "F.Paste")
			(net "LM75_2_A0")
		)
		(pad "2" smd circle
			(at 0.40005 0)
			(size 0 0)
			(layers "F.Cu" "F.Mask" "F.Paste")
			(net "P3V3_AUX")
		)
	)
)
